(kicad_pcb
	(version 20260206)
	(generator "pcbnew")
	(generator_version "10.0")
	(general
		(thickness 1.6)
		(legacy_teardrops no)
	)
	(paper "A4")
	(title_block
		(title "03242023_DA0F0TMBIJ0_F0T_Motherboard_J_brd_V01_OCP.brd")
		(comment 1 "Grand Teton / footprint 1952 of 6105 (J11), pads 113-224 of 291")
	)
	(layers
		(0 "F.Cu" signal "TOP")
		(4 "In1.Cu" signal "GND")
		(6 "In2.Cu" signal "IN1")
		(8 "In3.Cu" signal "GND1")
		(10 "In4.Cu" signal "IN2")
		(12 "In5.Cu" signal "GND2")
		(14 "In6.Cu" signal "IN3")
		(16 "In7.Cu" signal "GND3")
		(18 "In8.Cu" signal "VCC")
		(20 "In9.Cu" signal "VCC1")
		(22 "In10.Cu" signal "GND4")
		(24 "In11.Cu" signal "IN4")
		(26 "In12.Cu" signal "GND5")
		(28 "In13.Cu" signal "IN5")
		(30 "In14.Cu" signal "GND6")
		(32 "In15.Cu" signal "IN6")
		(34 "In16.Cu" signal "GND7")
		(2 "B.Cu" signal "BOTTOM")
		(9 "F.Adhes" user "F.Adhesive")
		(11 "B.Adhes" user "B.Adhesive")
		(13 "F.Paste" user "Package Geometry/Pastemask Top")
		(15 "B.Paste" user "Package Geometry/Pastemask Bottom")
		(5 "F.SilkS" user "Ref Des/Silkscreen Top")
		(7 "B.SilkS" user "Ref Des/Silkscreen Bottom")
		(1 "F.Mask" user "Board Geometry/Soldermask Top")
		(3 "B.Mask" user "Board Geometry/Soldermask Bottom")
		(17 "Dwgs.User" user "User.Drawings")
		(19 "Cmts.User" user "User.Comments")
		(21 "Eco1.User" user "User.Eco1")
		(23 "Eco2.User" user "User.Eco2")
		(25 "Edge.Cuts" user "Board Geometry/Outline")
		(27 "Margin" user)
		(31 "F.CrtYd" user "Package Geometry/Place Bound Top")
		(29 "B.CrtYd" user "Package Geometry/Place Bound Bottom")
		(35 "F.Fab" user "Ref Des/Assembly Top")
		(33 "B.Fab" user "Ref Des/Assembly Bottom")
	)
	(footprint ""
		(layer "F.Cu")
		(at 431.434748 -258.091686)
		(property "Reference" "J11"
			(at -3.683 -81.702148 0)
			(unlocked yes)
			(layer "F.SilkS")
			(effects
				(font
					(size 0.7874 0.5842)
					(thickness 0.1524)
				)
				(justify left)
			)
		)
		(property "Value" ""
			(at 0 0 0)
			(layer "F.Fab")
			(effects
				(font
					(size 1.27 1.27)
				)
			)
		)
		(duplicate_pad_numbers_are_jumpers no)
		(pad "113" smd rect
			(at -2.050034 36.975034 270)
			(size 0.519938 1.4986)
			(layers "F.Cu" "F.Mask" "F.Paste")
			(net "M_F_CPU0_SB_DQ<9>")
		)
		(pad "114" smd rect
			(at -2.050034 37.824918 270)
			(size 0.519938 1.4986)
			(layers "F.Cu" "F.Mask" "F.Paste")
			(net "GND")
		)
		(pad "115" smd rect
			(at -2.050034 38.675056 270)
			(size 0.519938 1.4986)
			(layers "F.Cu" "F.Mask" "F.Paste")
			(net "M_F_CPU0_SB_DQS_DP<1>")
		)
		(pad "116" smd rect
			(at -2.050034 39.52494 270)
			(size 0.519938 1.4986)
			(layers "F.Cu" "F.Mask" "F.Paste")
			(net "M_F_CPU0_SB_DQS_DN<1>")
		)
		(pad "117" smd rect
			(at -2.050034 40.375078 270)
			(size 0.519938 1.4986)
			(layers "F.Cu" "F.Mask" "F.Paste")
			(net "GND")
		)
		(pad "118" smd rect
			(at -2.050034 41.224962 270)
			(size 0.519938 1.4986)
			(layers "F.Cu" "F.Mask" "F.Paste")
			(net "M_F_CPU0_SB_DQ<12>")
		)
		(pad "119" smd rect
			(at -2.050034 42.0751 270)
			(size 0.519938 1.4986)
			(layers "F.Cu" "F.Mask" "F.Paste")
			(net "GND")
		)
		(pad "120" smd rect
			(at -2.050034 42.924984 270)
			(size 0.519938 1.4986)
			(layers "F.Cu" "F.Mask" "F.Paste")
			(net "M_F_CPU0_SB_DQ<13>")
		)
		(pad "121" smd rect
			(at -2.050034 43.775122 270)
			(size 0.519938 1.4986)
			(layers "F.Cu" "F.Mask" "F.Paste")
			(net "GND")
		)
		(pad "122" smd rect
			(at -2.050034 44.625006 270)
			(size 0.519938 1.4986)
			(layers "F.Cu" "F.Mask" "F.Paste")
			(net "M_F_CPU0_SB_DQ<16>")
		)
		(pad "123" smd rect
			(at -2.050034 45.47489 270)
			(size 0.519938 1.4986)
			(layers "F.Cu" "F.Mask" "F.Paste")
			(net "GND")
		)
		(pad "124" smd rect
			(at -2.050034 46.325028 270)
			(size 0.519938 1.4986)
			(layers "F.Cu" "F.Mask" "F.Paste")
			(net "M_F_CPU0_SB_DQ<17>")
		)
		(pad "125" smd rect
			(at -2.050034 47.174912 270)
			(size 0.519938 1.4986)
			(layers "F.Cu" "F.Mask" "F.Paste")
			(net "GND")
		)
		(pad "126" smd rect
			(at -2.050034 48.02505 270)
			(size 0.519938 1.4986)
			(layers "F.Cu" "F.Mask" "F.Paste")
			(net "M_F_CPU0_SB_DQS_DP<2>")
		)
		(pad "127" smd rect
			(at -2.050034 48.874934 270)
			(size 0.519938 1.4986)
			(layers "F.Cu" "F.Mask" "F.Paste")
			(net "M_F_CPU0_SB_DQS_DN<2>")
		)
		(pad "128" smd rect
			(at -2.050034 49.725072 270)
			(size 0.519938 1.4986)
			(layers "F.Cu" "F.Mask" "F.Paste")
			(net "GND")
		)
		(pad "129" smd rect
			(at -2.050034 50.574956 270)
			(size 0.519938 1.4986)
			(layers "F.Cu" "F.Mask" "F.Paste")
			(net "M_F_CPU0_SB_DQ<20>")
		)
		(pad "130" smd rect
			(at -2.050034 51.425094 270)
			(size 0.519938 1.4986)
			(layers "F.Cu" "F.Mask" "F.Paste")
			(net "GND")
		)
		(pad "131" smd rect
			(at -2.050034 52.274978 270)
			(size 0.519938 1.4986)
			(layers "F.Cu" "F.Mask" "F.Paste")
			(net "M_F_CPU0_SB_DQ<21>")
		)
		(pad "132" smd rect
			(at -2.050034 53.125116 270)
			(size 0.519938 1.4986)
			(layers "F.Cu" "F.Mask" "F.Paste")
			(net "GND")
		)
		(pad "133" smd rect
			(at -2.050034 53.975 270)
			(size 0.519938 1.4986)
			(layers "F.Cu" "F.Mask" "F.Paste")
			(net "M_F_CPU0_SB_DQ<24>")
		)
		(pad "134" smd rect
			(at -2.050034 54.824884 270)
			(size 0.519938 1.4986)
			(layers "F.Cu" "F.Mask" "F.Paste")
			(net "GND")
		)
		(pad "135" smd rect
			(at -2.050034 55.675022 270)
			(size 0.519938 1.4986)
			(layers "F.Cu" "F.Mask" "F.Paste")
			(net "M_F_CPU0_SB_DQ<25>")
		)
		(pad "136" smd rect
			(at -2.050034 56.524906 270)
			(size 0.519938 1.4986)
			(layers "F.Cu" "F.Mask" "F.Paste")
			(net "GND")
		)
		(pad "137" smd rect
			(at -2.050034 57.375044 270)
			(size 0.519938 1.4986)
			(layers "F.Cu" "F.Mask" "F.Paste")
			(net "M_F_CPU0_SB_DQS_DP<3>")
		)
		(pad "138" smd rect
			(at -2.050034 58.224928 270)
			(size 0.519938 1.4986)
			(layers "F.Cu" "F.Mask" "F.Paste")
			(net "M_F_CPU0_SB_DQS_DN<3>")
		)
		(pad "139" smd rect
			(at -2.050034 59.075066 270)
			(size 0.519938 1.4986)
			(layers "F.Cu" "F.Mask" "F.Paste")
			(net "GND")
		)
		(pad "140" smd rect
			(at -2.050034 59.92495 270)
			(size 0.519938 1.4986)
			(layers "F.Cu" "F.Mask" "F.Paste")
			(net "M_F_CPU0_SB_DQ<28>")
		)
		(pad "141" smd rect
			(at -2.050034 60.775088 270)
			(size 0.519938 1.4986)
			(layers "F.Cu" "F.Mask" "F.Paste")
			(net "GND")
		)
		(pad "142" smd rect
			(at -2.050034 61.624972 270)
			(size 0.519938 1.4986)
			(layers "F.Cu" "F.Mask" "F.Paste")
			(net "M_F_CPU0_SB_DQ<29>")
		)
		(pad "143" smd rect
			(at -2.050034 62.47511 270)
			(size 0.519938 1.4986)
			(layers "F.Cu" "F.Mask" "F.Paste")
			(net "GND")
		)
		(pad "144" smd rect
			(at -2.050034 63.324994 270)
			(size 0.519938 1.4986)
			(layers "F.Cu" "F.Mask" "F.Paste")
			(net "TP_CHF_CPU0_DIMM1_FRU_1")
		)
		(pad "145" smd rect
			(at 2.050034 -63.324994 270)
			(size 0.519938 1.4986)
			(layers "F.Cu" "F.Mask" "F.Paste")
			(net "P12V_S3_AUX_CPU0_NVDIMM")
		)
		(pad "146" smd rect
			(at 2.050034 -62.47511 270)
			(size 0.519938 1.4986)
			(layers "F.Cu" "F.Mask" "F.Paste")
			(net "P12V_S3_AUX_CPU0_NVDIMM")
		)
		(pad "147" smd rect
			(at 2.050034 -61.624972 270)
			(size 0.519938 1.4986)
			(layers "F.Cu" "F.Mask" "F.Paste")
			(net "PWRGD_CHF_CPU0_DIMM1")
		)
		(pad "148" smd rect
			(at 2.050034 -60.775088 270)
			(size 0.519938 1.4986)
			(layers "F.Cu" "F.Mask" "F.Paste")
			(net "PD_CHF_CPU0_DIMM1_SAA")
		)
		(pad "149" smd rect
			(at 2.050034 -59.92495 270)
			(size 0.519938 1.4986)
			(layers "F.Cu" "F.Mask" "F.Paste")
			(net "TP_CHF_CPU0_DIMM1_FRU_2")
		)
		(pad "150" smd rect
			(at 2.050034 -59.075066 270)
			(size 0.519938 1.4986)
			(layers "F.Cu" "F.Mask" "F.Paste")
			(net "TP_CHF_CPU0_DIMM1_FRU_3")
		)
		(pad "151" smd rect
			(at 2.050034 -58.224928 270)
			(size 0.519938 1.4986)
			(layers "F.Cu" "F.Mask" "F.Paste")
			(net "GND")
		)
		(pad "152" smd rect
			(at 2.050034 -57.375044 270)
			(size 0.519938 1.4986)
			(layers "F.Cu" "F.Mask" "F.Paste")
			(net "M_F_CPU0_SA_DQ<2>")
		)
		(pad "153" smd rect
			(at 2.050034 -56.524906 270)
			(size 0.519938 1.4986)
			(layers "F.Cu" "F.Mask" "F.Paste")
			(net "GND")
		)
		(pad "154" smd rect
			(at 2.050034 -55.675022 270)
			(size 0.519938 1.4986)
			(layers "F.Cu" "F.Mask" "F.Paste")
			(net "M_F_CPU0_SA_DQ<3>")
		)
		(pad "155" smd rect
			(at 2.050034 -54.824884 270)
			(size 0.519938 1.4986)
			(layers "F.Cu" "F.Mask" "F.Paste")
			(net "GND")
		)
		(pad "156" smd rect
			(at 2.050034 -53.975 270)
			(size 0.519938 1.4986)
			(layers "F.Cu" "F.Mask" "F.Paste")
			(net "M_F_CPU0_SA_DQS_DN<5>")
		)
		(pad "157" smd rect
			(at 2.050034 -53.125116 270)
			(size 0.519938 1.4986)
			(layers "F.Cu" "F.Mask" "F.Paste")
			(net "M_F_CPU0_SA_DQS_DP<5>")
		)
		(pad "158" smd rect
			(at 2.050034 -52.274978 270)
			(size 0.519938 1.4986)
			(layers "F.Cu" "F.Mask" "F.Paste")
			(net "GND")
		)
		(pad "159" smd rect
			(at 2.050034 -51.425094 270)
			(size 0.519938 1.4986)
			(layers "F.Cu" "F.Mask" "F.Paste")
			(net "M_F_CPU0_SA_DQ<6>")
		)
		(pad "160" smd rect
			(at 2.050034 -50.574956 270)
			(size 0.519938 1.4986)
			(layers "F.Cu" "F.Mask" "F.Paste")
			(net "GND")
		)
		(pad "161" smd rect
			(at 2.050034 -49.725072 270)
			(size 0.519938 1.4986)
			(layers "F.Cu" "F.Mask" "F.Paste")
			(net "M_F_CPU0_SA_DQ<7>")
		)
		(pad "162" smd rect
			(at 2.050034 -48.874934 270)
			(size 0.519938 1.4986)
			(layers "F.Cu" "F.Mask" "F.Paste")
			(net "GND")
		)
		(pad "163" smd rect
			(at 2.050034 -48.02505 270)
			(size 0.519938 1.4986)
			(layers "F.Cu" "F.Mask" "F.Paste")
			(net "M_F_CPU0_SA_DQ<10>")
		)
		(pad "164" smd rect
			(at 2.050034 -47.174912 270)
			(size 0.519938 1.4986)
			(layers "F.Cu" "F.Mask" "F.Paste")
			(net "GND")
		)
		(pad "165" smd rect
			(at 2.050034 -46.325028 270)
			(size 0.519938 1.4986)
			(layers "F.Cu" "F.Mask" "F.Paste")
			(net "M_F_CPU0_SA_DQ<11>")
		)
		(pad "166" smd rect
			(at 2.050034 -45.47489 270)
			(size 0.519938 1.4986)
			(layers "F.Cu" "F.Mask" "F.Paste")
			(net "GND")
		)
		(pad "167" smd rect
			(at 2.050034 -44.625006 270)
			(size 0.519938 1.4986)
			(layers "F.Cu" "F.Mask" "F.Paste")
			(net "M_F_CPU0_SA_DQS_DN<6>")
		)
		(pad "168" smd rect
			(at 2.050034 -43.775122 270)
			(size 0.519938 1.4986)
			(layers "F.Cu" "F.Mask" "F.Paste")
			(net "M_F_CPU0_SA_DQS_DP<6>")
		)
		(pad "169" smd rect
			(at 2.050034 -42.924984 270)
			(size 0.519938 1.4986)
			(layers "F.Cu" "F.Mask" "F.Paste")
			(net "GND")
		)
		(pad "170" smd rect
			(at 2.050034 -42.0751 270)
			(size 0.519938 1.4986)
			(layers "F.Cu" "F.Mask" "F.Paste")
			(net "M_F_CPU0_SA_DQ<14>")
		)
		(pad "171" smd rect
			(at 2.050034 -41.224962 270)
			(size 0.519938 1.4986)
			(layers "F.Cu" "F.Mask" "F.Paste")
			(net "GND")
		)
		(pad "172" smd rect
			(at 2.050034 -40.375078 270)
			(size 0.519938 1.4986)
			(layers "F.Cu" "F.Mask" "F.Paste")
			(net "M_F_CPU0_SA_DQ<15>")
		)
		(pad "173" smd rect
			(at 2.050034 -39.52494 270)
			(size 0.519938 1.4986)
			(layers "F.Cu" "F.Mask" "F.Paste")
			(net "GND")
		)
		(pad "174" smd rect
			(at 2.050034 -38.675056 270)
			(size 0.519938 1.4986)
			(layers "F.Cu" "F.Mask" "F.Paste")
			(net "M_F_CPU0_SA_DQ<18>")
		)
		(pad "175" smd rect
			(at 2.050034 -37.824918 270)
			(size 0.519938 1.4986)
			(layers "F.Cu" "F.Mask" "F.Paste")
			(net "GND")
		)
		(pad "176" smd rect
			(at 2.050034 -36.975034 270)
			(size 0.519938 1.4986)
			(layers "F.Cu" "F.Mask" "F.Paste")
			(net "M_F_CPU0_SA_DQ<19>")
		)
		(pad "177" smd rect
			(at 2.050034 -36.124896 270)
			(size 0.519938 1.4986)
			(layers "F.Cu" "F.Mask" "F.Paste")
			(net "GND")
		)
		(pad "178" smd rect
			(at 2.050034 -35.275012 270)
			(size 0.519938 1.4986)
			(layers "F.Cu" "F.Mask" "F.Paste")
			(net "M_F_CPU0_SA_DQS_DN<7>")
		)
		(pad "179" smd rect
			(at 2.050034 -34.425128 270)
			(size 0.519938 1.4986)
			(layers "F.Cu" "F.Mask" "F.Paste")
			(net "M_F_CPU0_SA_DQS_DP<7>")
		)
		(pad "180" smd rect
			(at 2.050034 -33.57499 270)
			(size 0.519938 1.4986)
			(layers "F.Cu" "F.Mask" "F.Paste")
			(net "GND")
		)
		(pad "181" smd rect
			(at 2.050034 -32.725106 270)
			(size 0.519938 1.4986)
			(layers "F.Cu" "F.Mask" "F.Paste")
			(net "M_F_CPU0_SA_DQ<22>")
		)
		(pad "182" smd rect
			(at 2.050034 -31.874968 270)
			(size 0.519938 1.4986)
			(layers "F.Cu" "F.Mask" "F.Paste")
			(net "GND")
		)
		(pad "183" smd rect
			(at 2.050034 -31.025084 270)
			(size 0.519938 1.4986)
			(layers "F.Cu" "F.Mask" "F.Paste")
			(net "M_F_CPU0_SA_DQ<23>")
		)
		(pad "184" smd rect
			(at 2.050034 -30.174946 270)
			(size 0.519938 1.4986)
			(layers "F.Cu" "F.Mask" "F.Paste")
			(net "GND")
		)
		(pad "185" smd rect
			(at 2.050034 -29.325062 270)
			(size 0.519938 1.4986)
			(layers "F.Cu" "F.Mask" "F.Paste")
			(net "M_F_CPU0_SA_DQ<26>")
		)
		(pad "186" smd rect
			(at 2.050034 -28.474924 270)
			(size 0.519938 1.4986)
			(layers "F.Cu" "F.Mask" "F.Paste")
			(net "GND")
		)
		(pad "187" smd rect
			(at 2.050034 -27.62504 270)
			(size 0.519938 1.4986)
			(layers "F.Cu" "F.Mask" "F.Paste")
			(net "M_F_CPU0_SA_DQ<27>")
		)
		(pad "188" smd rect
			(at 2.050034 -26.774902 270)
			(size 0.519938 1.4986)
			(layers "F.Cu" "F.Mask" "F.Paste")
			(net "GND")
		)
		(pad "189" smd rect
			(at 2.050034 -25.925018 270)
			(size 0.519938 1.4986)
			(layers "F.Cu" "F.Mask" "F.Paste")
			(net "M_F_CPU0_SA_DQS_DN<8>")
		)
		(pad "190" smd rect
			(at 2.050034 -25.07488 270)
			(size 0.519938 1.4986)
			(layers "F.Cu" "F.Mask" "F.Paste")
			(net "M_F_CPU0_SA_DQS_DP<8>")
		)
		(pad "191" smd rect
			(at 2.050034 -24.224996 270)
			(size 0.519938 1.4986)
			(layers "F.Cu" "F.Mask" "F.Paste")
			(net "GND")
		)
		(pad "192" smd rect
			(at 2.050034 -23.375112 270)
			(size 0.519938 1.4986)
			(layers "F.Cu" "F.Mask" "F.Paste")
			(net "M_F_CPU0_SA_DQ<30>")
		)
		(pad "193" smd rect
			(at 2.050034 -22.524974 270)
			(size 0.519938 1.4986)
			(layers "F.Cu" "F.Mask" "F.Paste")
			(net "GND")
		)
		(pad "194" smd rect
			(at 2.050034 -21.67509 270)
			(size 0.519938 1.4986)
			(layers "F.Cu" "F.Mask" "F.Paste")
			(net "M_F_CPU0_SA_DQ<31>")
		)
		(pad "195" smd rect
			(at 2.050034 -20.824952 270)
			(size 0.519938 1.4986)
			(layers "F.Cu" "F.Mask" "F.Paste")
			(net "GND")
		)
		(pad "196" smd rect
			(at 2.050034 -19.975068 270)
			(size 0.519938 1.4986)
			(layers "F.Cu" "F.Mask" "F.Paste")
			(net "M_F_CPU0_SA_CB<2>")
		)
		(pad "197" smd rect
			(at 2.050034 -19.12493 270)
			(size 0.519938 1.4986)
			(layers "F.Cu" "F.Mask" "F.Paste")
			(net "GND")
		)
		(pad "198" smd rect
			(at 2.050034 -18.275046 270)
			(size 0.519938 1.4986)
			(layers "F.Cu" "F.Mask" "F.Paste")
			(net "M_F_CPU0_SA_CB<3>")
		)
		(pad "199" smd rect
			(at 2.050034 -17.424908 270)
			(size 0.519938 1.4986)
			(layers "F.Cu" "F.Mask" "F.Paste")
			(net "GND")
		)
		(pad "200" smd rect
			(at 2.050034 -16.575024 270)
			(size 0.519938 1.4986)
			(layers "F.Cu" "F.Mask" "F.Paste")
			(net "M_F_CPU0_SA_DQS_DN<9>")
		)
		(pad "201" smd rect
			(at 2.050034 -15.724886 270)
			(size 0.519938 1.4986)
			(layers "F.Cu" "F.Mask" "F.Paste")
			(net "M_F_CPU0_SA_DQS_DP<9>")
		)
		(pad "202" smd rect
			(at 2.050034 -14.875002 270)
			(size 0.519938 1.4986)
			(layers "F.Cu" "F.Mask" "F.Paste")
			(net "GND")
		)
		(pad "203" smd rect
			(at 2.050034 -14.025118 270)
			(size 0.519938 1.4986)
			(layers "F.Cu" "F.Mask" "F.Paste")
			(net "M_F_CPU0_SA_CB<6>")
		)
		(pad "204" smd rect
			(at 2.050034 -13.17498 270)
			(size 0.519938 1.4986)
			(layers "F.Cu" "F.Mask" "F.Paste")
			(net "GND")
		)
		(pad "205" smd rect
			(at 2.050034 -12.325096 270)
			(size 0.519938 1.4986)
			(layers "F.Cu" "F.Mask" "F.Paste")
			(net "M_F_CPU0_SA_CB<7>")
		)
		(pad "206" smd rect
			(at 2.050034 -11.474958 270)
			(size 0.519938 1.4986)
			(layers "F.Cu" "F.Mask" "F.Paste")
			(net "GND")
		)
		(pad "207" smd rect
			(at 2.050034 -10.625074 270)
			(size 0.519938 1.4986)
			(layers "F.Cu" "F.Mask" "F.Paste")
			(net "RST_M_EF_CPU0_FPGA_N")
		)
		(pad "208" smd rect
			(at 2.050034 -9.774936 270)
			(size 0.519938 1.4986)
			(layers "F.Cu" "F.Mask" "F.Paste")
			(net "GND")
		)
		(pad "209" smd rect
			(at 2.050034 -8.925052 270)
			(size 0.519938 1.4986)
			(layers "F.Cu" "F.Mask" "F.Paste")
			(net "M_F_CPU0_SA_CS_N<1>")
		)
		(pad "210" smd rect
			(at 2.050034 -8.074914 270)
			(size 0.519938 1.4986)
			(layers "F.Cu" "F.Mask" "F.Paste")
			(net "GND")
		)
		(pad "211" smd rect
			(at 2.050034 -7.22503 270)
			(size 0.519938 1.4986)
			(layers "F.Cu" "F.Mask" "F.Paste")
			(net "M_F_CPU0_SA_CA<1>")
		)
		(pad "212" smd rect
			(at 2.050034 -6.374892 270)
			(size 0.519938 1.4986)
			(layers "F.Cu" "F.Mask" "F.Paste")
			(net "GND")
		)
		(pad "213" smd rect
			(at 2.050034 -5.525008 270)
			(size 0.519938 1.4986)
			(layers "F.Cu" "F.Mask" "F.Paste")
			(net "M_F_CPU0_SA_CA<3>")
		)
		(pad "214" smd rect
			(at 2.050034 -4.675124 270)
			(size 0.519938 1.4986)
			(layers "F.Cu" "F.Mask" "F.Paste")
			(net "GND")
		)
		(pad "215" smd rect
			(at 2.050034 -3.824986 270)
			(size 0.519938 1.4986)
			(layers "F.Cu" "F.Mask" "F.Paste")
			(net "M_F_CPU0_SA_CA<5>")
		)
		(pad "216" smd rect
			(at 2.050034 -2.975102 270)
			(size 0.519938 1.4986)
			(layers "F.Cu" "F.Mask" "F.Paste")
			(net "GND")
		)
		(pad "217" smd rect
			(at 2.050034 -2.124964 270)
			(size 0.519938 1.4986)
			(layers "F.Cu" "F.Mask" "F.Paste")
			(net "M_F_CPU0_CLK_DP<0>")
		)
		(pad "218" smd rect
			(at 2.050034 -1.27508 270)
			(size 0.519938 1.4986)
			(layers "F.Cu" "F.Mask" "F.Paste")
			(net "M_F_CPU0_CLK_DN<0>")
		)
		(pad "219" smd rect
			(at 2.050034 -0.424942 270)
			(size 0.519938 1.4986)
			(layers "F.Cu" "F.Mask" "F.Paste")
			(net "GND")
		)
		(pad "220" smd rect
			(at 2.050034 5.525008 270)
			(size 0.519938 1.4986)
			(layers "F.Cu" "F.Mask" "F.Paste")
			(net "TP_CHF_CPU0_DIMM1_FRU_4")
		)
		(pad "221" smd rect
			(at 2.050034 6.374892 270)
			(size 0.519938 1.4986)
			(layers "F.Cu" "F.Mask" "F.Paste")
			(net "M_F_CPU0_SB_CA<1>")
		)
		(pad "222" smd rect
			(at 2.050034 7.22503 270)
			(size 0.519938 1.4986)
			(layers "F.Cu" "F.Mask" "F.Paste")
			(net "GND")
		)
		(pad "223" smd rect
			(at 2.050034 8.074914 270)
			(size 0.519938 1.4986)
			(layers "F.Cu" "F.Mask" "F.Paste")
			(net "M_F_CPU0_SB_CA<3>")
		)
		(pad "224" smd rect
			(at 2.050034 8.925052 270)
			(size 0.519938 1.4986)
			(layers "F.Cu" "F.Mask" "F.Paste")
			(net "GND")
		)
	)
)
